(kicad_pcb
	(version 20260206)
	(generator "pcbnew")
	(generator_version "10.0")
	(general
		(thickness 1.6)
		(legacy_teardrops no)
	)
	(paper "A4")
	(title_block
		(title "9052_F0T_PDB_Converter_Brick_F_V03_1208_1600_OCP.brd")
		(comment 1 "Grand Teton / footprints 578-578 of 578")
	)
	(layers
		(0 "F.Cu" signal "TOP")
		(4 "In1.Cu" signal "GND")
		(6 "In2.Cu" signal "IN1")
		(8 "In3.Cu" signal "GND1")
		(10 "In4.Cu" signal "VCC")
		(12 "In5.Cu" signal "VCC1")
		(14 "In6.Cu" signal "GND2")
		(16 "In7.Cu" signal "IN2")
		(18 "In8.Cu" signal "GND3")
		(2 "B.Cu" signal "BOTTOM")
		(9 "F.Adhes" user "F.Adhesive")
		(11 "B.Adhes" user "B.Adhesive")
		(13 "F.Paste" user "Package Geometry/Pastemask Top")
		(15 "B.Paste" user "Package Geometry/Pastemask Bottom")
		(5 "F.SilkS" user "Ref Des/Silkscreen Top")
		(7 "B.SilkS" user "Ref Des/Silkscreen Bottom")
		(1 "F.Mask" user "Board Geometry/Soldermask Top")
		(3 "B.Mask" user "Board Geometry/Soldermask Bottom")
		(17 "Dwgs.User" user "User.Drawings")
		(19 "Cmts.User" user "User.Comments")
		(21 "Eco1.User" user "User.Eco1")
		(23 "Eco2.User" user "User.Eco2")
		(25 "Edge.Cuts" user "Board Geometry/Outline")
		(27 "Margin" user)
		(31 "F.CrtYd" user "Package Geometry/Place Bound Top")
		(29 "B.CrtYd" user "Package Geometry/Place Bound Bottom")
		(35 "F.Fab" user "Ref Des/Assembly Top")
		(33 "B.Fab" user "Ref Des/Assembly Bottom")
	)
	(footprint ""
		(layer "B.Cu")
		(at 223.012 -90.043 -90)
		(property "Reference" "R37"
			(at 0 0 90)
			(layer "B.SilkS")
			(hide yes)
			(effects
				(font
					(size 1.27 1.27)
				)
				(justify mirror)
			)
		)
		(property "Value" ""
			(at 0 0 90)
			(layer "B.Fab")
			(effects
				(font
					(size 1.27 1.27)
				)
				(justify mirror)
			)
		)
		(duplicate_pad_numbers_are_jumpers no)
		(fp_line
			(start -0.7874 0.4064)
			(end 0.7874 0.4064)
			(stroke
				(width 0.1524)
				(type default)
			)
			(layer "B.SilkS")
		)
		(fp_line
			(start 0.7874 0.4064)
			(end 0.7874 -0.4064)
			(stroke
				(width 0.1524)
				(type default)
			)
			(layer "B.SilkS")
		)
		(fp_line
			(start -0.7874 -0.4064)
			(end -0.7874 0.4064)
			(stroke
				(width 0.1524)
				(type default)
			)
			(layer "B.SilkS")
		)
		(fp_line
			(start 0.7874 -0.4064)
			(end -0.7874 -0.4064)
			(stroke
				(width 0.1524)
				(type default)
			)
			(layer "B.SilkS")
		)
		(fp_line
			(start -0.67945 0.3048)
			(end -0.120396 0.3048)
			(stroke
				(width 0.1)
				(type default)
			)
			(layer "B.Fab")
		)
		(fp_line
			(start -0.120396 0.3048)
			(end -0.120396 0.2794)
			(stroke
				(width 0.1)
				(type default)
			)
			(layer "B.Fab")
		)
		(fp_line
			(start 0.12065 0.3048)
			(end 0.67945 0.3048)
			(stroke
				(width 0.1)
				(type default)
			)
			(layer "B.Fab")
		)
		(fp_line
			(start 0.67945 0.3048)
			(end 0.67945 -0.305054)
			(stroke
				(width 0.1)
				(type default)
			)
			(layer "B.Fab")
		)
		(fp_line
			(start -0.120396 0.2794)
			(end 0.12065 0.2794)
			(stroke
				(width 0.1)
				(type default)
			)
			(layer "B.Fab")
		)
		(fp_line
			(start 0.12065 0.2794)
			(end 0.12065 0.3048)
			(stroke
				(width 0.1)
				(type default)
			)
			(layer "B.Fab")
		)
		(fp_line
			(start -0.12065 -0.2794)
			(end -0.12065 -0.3048)
			(stroke
				(width 0.1)
				(type default)
			)
			(layer "B.Fab")
		)
		(fp_line
			(start 0.12065 -0.2794)
			(end -0.12065 -0.2794)
			(stroke
				(width 0.1)
				(type default)
			)
			(layer "B.Fab")
		)
		(fp_line
			(start -0.67945 -0.3048)
			(end -0.67945 0.3048)
			(stroke
				(width 0.1)
				(type default)
			)
			(layer "B.Fab")
		)
		(fp_line
			(start -0.12065 -0.3048)
			(end -0.67945 -0.3048)
			(stroke
				(width 0.1)
				(type default)
			)
			(layer "B.Fab")
		)
		(fp_line
			(start 0.12065 -0.305054)
			(end 0.12065 -0.2794)
			(stroke
				(width 0.1)
				(type default)
			)
			(layer "B.Fab")
		)
		(fp_line
			(start 0.67945 -0.305054)
			(end 0.12065 -0.305054)
			(stroke
				(width 0.1)
				(type default)
			)
			(layer "B.Fab")
		)
		(pad "1" smd circle
			(at 0.40005 0 90)
			(size 0 0)
			(layers "B.Cu" "B.Mask" "B.Paste")
			(net "FRU_WP_N")
		)
		(pad "2" smd circle
			(at -0.40005 0 90)
			(size 0 0)
			(layers "B.Cu" "B.Mask" "B.Paste")
			(net "GND")
		)
	)
)
